(kicad_pcb
	(version 20260206)
	(generator "pcbnew")
	(generator_version "10.0")
	(general
		(thickness 1.6)
		(legacy_teardrops no)
	)
	(paper "A4")
	(title_block
		(title "01162023_DA0F0TEBIF0_F0T_Expander_BD_F_brd_V02_OCP.brd")
		(comment 1 "Grand Teton / footprints 3436-3442 of 9728")
	)
	(layers
		(0 "F.Cu" signal "TOP")
		(4 "In1.Cu" signal "GND")
		(6 "In2.Cu" signal "VCC")
		(8 "In3.Cu" signal "VCC1")
		(10 "In4.Cu" signal "GND1")
		(12 "In5.Cu" signal "IN1")
		(14 "In6.Cu" signal "GND2")
		(16 "In7.Cu" signal "IN2")
		(18 "In8.Cu" signal "GND3")
		(20 "In9.Cu" signal "IN3")
		(22 "In10.Cu" signal "GND4")
		(24 "In11.Cu" signal "IN4")
		(26 "In12.Cu" signal "GND5")
		(28 "In13.Cu" signal "IN5")
		(30 "In14.Cu" signal "GND6")
		(32 "In15.Cu" signal "IN6")
		(34 "In16.Cu" signal "GND7")
		(2 "B.Cu" signal "BOTTOM")
		(9 "F.Adhes" user "F.Adhesive")
		(11 "B.Adhes" user "B.Adhesive")
		(13 "F.Paste" user "Package Geometry/Pastemask Top")
		(15 "B.Paste" user "Package Geometry/Pastemask Bottom")
		(5 "F.SilkS" user "Ref Des/Silkscreen Top")
		(7 "B.SilkS" user "Ref Des/Silkscreen Bottom")
		(1 "F.Mask" user "Board Geometry/Soldermask Top")
		(3 "B.Mask" user "Board Geometry/Soldermask Bottom")
		(17 "Dwgs.User" user "User.Drawings")
		(19 "Cmts.User" user "User.Comments")
		(21 "Eco1.User" user "User.Eco1")
		(23 "Eco2.User" user "User.Eco2")
		(25 "Edge.Cuts" user "Board Geometry/Outline")
		(27 "Margin" user)
		(31 "F.CrtYd" user "Package Geometry/Place Bound Top")
		(29 "B.CrtYd" user "Package Geometry/Place Bound Bottom")
		(35 "F.Fab" user "Ref Des/Assembly Top")
		(33 "B.Fab" user "Ref Des/Assembly Bottom")
	)
	(footprint ""
		(layer "F.Cu")
		(at 235.623608 -147.720812)
		(property "Reference" "R4221"
			(at 0 0 0)
			(layer "F.SilkS")
			(hide yes)
			(effects
				(font
					(size 1.27 1.27)
				)
			)
		)
		(property "Value" ""
			(at 0 0 0)
			(layer "F.Fab")
			(effects
				(font
					(size 1.27 1.27)
				)
			)
		)
		(duplicate_pad_numbers_are_jumpers no)
		(fp_line
			(start -0.7874 -0.4064)
			(end 0.7874 -0.4064)
			(stroke
				(width 0.1524)
				(type default)
			)
			(layer "F.SilkS")
		)
		(fp_line
			(start -0.7874 0.4064)
			(end -0.7874 -0.4064)
			(stroke
				(width 0.1524)
				(type default)
			)
			(layer "F.SilkS")
		)
		(fp_line
			(start 0.7874 -0.4064)
			(end 0.7874 0.4064)
			(stroke
				(width 0.1524)
				(type default)
			)
			(layer "F.SilkS")
		)
		(fp_line
			(start 0.7874 0.4064)
			(end -0.7874 0.4064)
			(stroke
				(width 0.1524)
				(type default)
			)
			(layer "F.SilkS")
		)
		(fp_line
			(start -0.67945 -0.305054)
			(end -0.12065 -0.305054)
			(stroke
				(width 0.1)
				(type default)
			)
			(layer "F.Fab")
		)
		(fp_line
			(start -0.67945 0.3048)
			(end -0.67945 -0.305054)
			(stroke
				(width 0.1)
				(type default)
			)
			(layer "F.Fab")
		)
		(fp_line
			(start -0.12065 -0.305054)
			(end -0.12065 -0.2794)
			(stroke
				(width 0.1)
				(type default)
			)
			(layer "F.Fab")
		)
		(fp_line
			(start -0.12065 -0.2794)
			(end 0.12065 -0.2794)
			(stroke
				(width 0.1)
				(type default)
			)
			(layer "F.Fab")
		)
		(fp_line
			(start -0.12065 0.2794)
			(end -0.12065 0.3048)
			(stroke
				(width 0.1)
				(type default)
			)
			(layer "F.Fab")
		)
		(fp_line
			(start -0.12065 0.3048)
			(end -0.67945 0.3048)
			(stroke
				(width 0.1)
				(type default)
			)
			(layer "F.Fab")
		)
		(fp_line
			(start 0.120396 0.2794)
			(end -0.12065 0.2794)
			(stroke
				(width 0.1)
				(type default)
			)
			(layer "F.Fab")
		)
		(fp_line
			(start 0.120396 0.3048)
			(end 0.120396 0.2794)
			(stroke
				(width 0.1)
				(type default)
			)
			(layer "F.Fab")
		)
		(fp_line
			(start 0.12065 -0.3048)
			(end 0.67945 -0.3048)
			(stroke
				(width 0.1)
				(type default)
			)
			(layer "F.Fab")
		)
		(fp_line
			(start 0.12065 -0.2794)
			(end 0.12065 -0.3048)
			(stroke
				(width 0.1)
				(type default)
			)
			(layer "F.Fab")
		)
		(fp_line
			(start 0.67945 -0.3048)
			(end 0.67945 0.3048)
			(stroke
				(width 0.1)
				(type default)
			)
			(layer "F.Fab")
		)
		(fp_line
			(start 0.67945 0.3048)
			(end 0.120396 0.3048)
			(stroke
				(width 0.1)
				(type default)
			)
			(layer "F.Fab")
		)
		(pad "1" smd circle
			(at -0.40005 0)
			(size 0 0)
			(layers "F.Cu" "F.Mask" "F.Paste")
			(net "CLK_GEN_CK440_PEX_OE4_N")
		)
		(pad "2" smd circle
			(at 0.40005 0)
			(size 0 0)
			(layers "F.Cu" "F.Mask" "F.Paste")
			(net "P3V3")
		)
	)
	(footprint ""
		(layer "F.Cu")
		(at 236.492288 -97.258378 -90)
		(property "Reference" "R1009"
			(at 0 0 270)
			(layer "F.SilkS")
			(hide yes)
			(effects
				(font
					(size 1.27 1.27)
				)
			)
		)
		(property "Value" ""
			(at 0 0 270)
			(layer "F.Fab")
			(effects
				(font
					(size 1.27 1.27)
				)
			)
		)
		(duplicate_pad_numbers_are_jumpers no)
		(fp_line
			(start -0.7874 0.4064)
			(end -0.7874 -0.4064)
			(stroke
				(width 0.1524)
				(type default)
			)
			(layer "F.SilkS")
		)
		(fp_line
			(start 0.7874 0.4064)
			(end -0.7874 0.4064)
			(stroke
				(width 0.1524)
				(type default)
			)
			(layer "F.SilkS")
		)
		(fp_line
			(start -0.7874 -0.4064)
			(end 0.7874 -0.4064)
			(stroke
				(width 0.1524)
				(type default)
			)
			(layer "F.SilkS")
		)
		(fp_line
			(start 0.7874 -0.4064)
			(end 0.7874 0.4064)
			(stroke
				(width 0.1524)
				(type default)
			)
			(layer "F.SilkS")
		)
		(fp_line
			(start -0.67945 0.3048)
			(end -0.67945 -0.305054)
			(stroke
				(width 0.1)
				(type default)
			)
			(layer "F.Fab")
		)
		(fp_line
			(start -0.12065 0.3048)
			(end -0.67945 0.3048)
			(stroke
				(width 0.1)
				(type default)
			)
			(layer "F.Fab")
		)
		(fp_line
			(start 0.120396 0.3048)
			(end 0.120396 0.2794)
			(stroke
				(width 0.1)
				(type default)
			)
			(layer "F.Fab")
		)
		(fp_line
			(start 0.67945 0.3048)
			(end 0.120396 0.3048)
			(stroke
				(width 0.1)
				(type default)
			)
			(layer "F.Fab")
		)
		(fp_line
			(start -0.12065 0.2794)
			(end -0.12065 0.3048)
			(stroke
				(width 0.1)
				(type default)
			)
			(layer "F.Fab")
		)
		(fp_line
			(start 0.120396 0.2794)
			(end -0.12065 0.2794)
			(stroke
				(width 0.1)
				(type default)
			)
			(layer "F.Fab")
		)
		(fp_line
			(start -0.12065 -0.2794)
			(end 0.12065 -0.2794)
			(stroke
				(width 0.1)
				(type default)
			)
			(layer "F.Fab")
		)
		(fp_line
			(start 0.12065 -0.2794)
			(end 0.12065 -0.3048)
			(stroke
				(width 0.1)
				(type default)
			)
			(layer "F.Fab")
		)
		(fp_line
			(start 0.12065 -0.3048)
			(end 0.67945 -0.3048)
			(stroke
				(width 0.1)
				(type default)
			)
			(layer "F.Fab")
		)
		(fp_line
			(start 0.67945 -0.3048)
			(end 0.67945 0.3048)
			(stroke
				(width 0.1)
				(type default)
			)
			(layer "F.Fab")
		)
		(fp_line
			(start -0.67945 -0.305054)
			(end -0.12065 -0.305054)
			(stroke
				(width 0.1)
				(type default)
			)
			(layer "F.Fab")
		)
		(fp_line
			(start -0.12065 -0.305054)
			(end -0.12065 -0.2794)
			(stroke
				(width 0.1)
				(type default)
			)
			(layer "F.Fab")
		)
		(pad "1" smd circle
			(at -0.40005 0 270)
			(size 0 0)
			(layers "F.Cu" "F.Mask" "F.Paste")
			(net "P3V3_AUX")
		)
		(pad "2" smd circle
			(at 0.40005 0 270)
			(size 0 0)
			(layers "F.Cu" "F.Mask" "F.Paste")
			(net "RST_PEX_USB_HUB_R_N")
		)
	)
	(footprint ""
		(layer "F.Cu")
		(at 456.271376 -258.331208 -90)
		(property "Reference" "R6554"
			(at 0 0 270)
			(layer "F.SilkS")
			(hide yes)
			(effects
				(font
					(size 1.27 1.27)
				)
			)
		)
		(property "Value" ""
			(at 0 0 270)
			(layer "F.Fab")
			(effects
				(font
					(size 1.27 1.27)
				)
			)
		)
		(duplicate_pad_numbers_are_jumpers no)
		(fp_line
			(start -0.7874 0.4064)
			(end -0.7874 -0.4064)
			(stroke
				(width 0.1524)
				(type default)
			)
			(layer "F.SilkS")
		)
		(fp_line
			(start 0.7874 0.4064)
			(end -0.7874 0.4064)
			(stroke
				(width 0.1524)
				(type default)
			)
			(layer "F.SilkS")
		)
		(fp_line
			(start -0.7874 -0.4064)
			(end 0.7874 -0.4064)
			(stroke
				(width 0.1524)
				(type default)
			)
			(layer "F.SilkS")
		)
		(fp_line
			(start 0.7874 -0.4064)
			(end 0.7874 0.4064)
			(stroke
				(width 0.1524)
				(type default)
			)
			(layer "F.SilkS")
		)
		(fp_line
			(start -0.67945 0.3048)
			(end -0.67945 -0.305054)
			(stroke
				(width 0.1)
				(type default)
			)
			(layer "F.Fab")
		)
		(fp_line
			(start -0.12065 0.3048)
			(end -0.67945 0.3048)
			(stroke
				(width 0.1)
				(type default)
			)
			(layer "F.Fab")
		)
		(fp_line
			(start 0.120396 0.3048)
			(end 0.120396 0.2794)
			(stroke
				(width 0.1)
				(type default)
			)
			(layer "F.Fab")
		)
		(fp_line
			(start 0.67945 0.3048)
			(end 0.120396 0.3048)
			(stroke
				(width 0.1)
				(type default)
			)
			(layer "F.Fab")
		)
		(fp_line
			(start -0.12065 0.2794)
			(end -0.12065 0.3048)
			(stroke
				(width 0.1)
				(type default)
			)
			(layer "F.Fab")
		)
		(fp_line
			(start 0.120396 0.2794)
			(end -0.12065 0.2794)
			(stroke
				(width 0.1)
				(type default)
			)
			(layer "F.Fab")
		)
		(fp_line
			(start -0.12065 -0.2794)
			(end 0.12065 -0.2794)
			(stroke
				(width 0.1)
				(type default)
			)
			(layer "F.Fab")
		)
		(fp_line
			(start 0.12065 -0.2794)
			(end 0.12065 -0.3048)
			(stroke
				(width 0.1)
				(type default)
			)
			(layer "F.Fab")
		)
		(fp_line
			(start 0.12065 -0.3048)
			(end 0.67945 -0.3048)
			(stroke
				(width 0.1)
				(type default)
			)
			(layer "F.Fab")
		)
		(fp_line
			(start 0.67945 -0.3048)
			(end 0.67945 0.3048)
			(stroke
				(width 0.1)
				(type default)
			)
			(layer "F.Fab")
		)
		(fp_line
			(start -0.67945 -0.305054)
			(end -0.12065 -0.305054)
			(stroke
				(width 0.1)
				(type default)
			)
			(layer "F.Fab")
		)
		(fp_line
			(start -0.12065 -0.305054)
			(end -0.12065 -0.2794)
			(stroke
				(width 0.1)
				(type default)
			)
			(layer "F.Fab")
		)
		(pad "1" smd circle
			(at -0.40005 0 270)
			(size 0 0)
			(layers "F.Cu" "F.Mask" "F.Paste")
			(net "P1V25_SERDES_VDDPLL_PEX3")
		)
		(pad "2" smd circle
			(at 0.40005 0 270)
			(size 0 0)
			(layers "F.Cu" "F.Mask" "F.Paste")
			(net "P1V25_SERDES_VDDPLL_PEX3_C3")
		)
	)
	(footprint ""
		(layer "F.Cu")
		(at 442.794136 -117.426486)
		(property "Reference" "PC916"
			(at 0 0 0)
			(layer "F.SilkS")
			(hide yes)
			(effects
				(font
					(size 1.27 1.27)
				)
			)
		)
		(property "Value" ""
			(at 0 0 0)
			(layer "F.Fab")
			(effects
				(font
					(size 1.27 1.27)
				)
			)
		)
		(duplicate_pad_numbers_are_jumpers no)
		(fp_line
			(start -0.7874 -0.4064)
			(end 0.7874 -0.4064)
			(stroke
				(width 0.1524)
				(type default)
			)
			(layer "F.SilkS")
		)
		(fp_line
			(start -0.7874 0.4064)
			(end -0.7874 -0.4064)
			(stroke
				(width 0.1524)
				(type default)
			)
			(layer "F.SilkS")
		)
		(fp_line
			(start 0.7874 -0.4064)
			(end 0.7874 0.4064)
			(stroke
				(width 0.1524)
				(type default)
			)
			(layer "F.SilkS")
		)
		(fp_line
			(start 0.7874 0.4064)
			(end -0.7874 0.4064)
			(stroke
				(width 0.1524)
				(type default)
			)
			(layer "F.SilkS")
		)
		(fp_line
			(start -0.67945 -0.305054)
			(end -0.12065 -0.305054)
			(stroke
				(width 0.1)
				(type default)
			)
			(layer "F.Fab")
		)
		(fp_line
			(start -0.67945 0.3048)
			(end -0.67945 -0.305054)
			(stroke
				(width 0.1)
				(type default)
			)
			(layer "F.Fab")
		)
		(fp_line
			(start -0.12065 -0.305054)
			(end -0.12065 -0.2794)
			(stroke
				(width 0.1)
				(type default)
			)
			(layer "F.Fab")
		)
		(fp_line
			(start -0.12065 -0.2794)
			(end 0.12065 -0.2794)
			(stroke
				(width 0.1)
				(type default)
			)
			(layer "F.Fab")
		)
		(fp_line
			(start -0.12065 0.2794)
			(end -0.12065 0.3048)
			(stroke
				(width 0.1)
				(type default)
			)
			(layer "F.Fab")
		)
		(fp_line
			(start -0.12065 0.3048)
			(end -0.67945 0.3048)
			(stroke
				(width 0.1)
				(type default)
			)
			(layer "F.Fab")
		)
		(fp_line
			(start 0.120396 0.2794)
			(end -0.12065 0.2794)
			(stroke
				(width 0.1)
				(type default)
			)
			(layer "F.Fab")
		)
		(fp_line
			(start 0.120396 0.3048)
			(end 0.120396 0.2794)
			(stroke
				(width 0.1)
				(type default)
			)
			(layer "F.Fab")
		)
		(fp_line
			(start 0.12065 -0.3048)
			(end 0.67945 -0.3048)
			(stroke
				(width 0.1)
				(type default)
			)
			(layer "F.Fab")
		)
		(fp_line
			(start 0.12065 -0.2794)
			(end 0.12065 -0.3048)
			(stroke
				(width 0.1)
				(type default)
			)
			(layer "F.Fab")
		)
		(fp_line
			(start 0.67945 -0.3048)
			(end 0.67945 0.3048)
			(stroke
				(width 0.1)
				(type default)
			)
			(layer "F.Fab")
		)
		(fp_line
			(start 0.67945 0.3048)
			(end 0.120396 0.3048)
			(stroke
				(width 0.1)
				(type default)
			)
			(layer "F.Fab")
		)
		(pad "1" smd circle
			(at -0.40005 0)
			(size 0 0)
			(layers "F.Cu" "F.Mask" "F.Paste")
			(net "P3V3_NIC7_CO_MODE")
		)
		(pad "2" smd circle
			(at 0.40005 0)
			(size 0 0)
			(layers "F.Cu" "F.Mask" "F.Paste")
			(net "GND")
		)
	)
	(footprint ""
		(layer "F.Cu")
		(at 330.835 -239.395 180)
		(property "Reference" "C2744"
			(at 0 0 180)
			(layer "F.SilkS")
			(hide yes)
			(effects
				(font
					(size 1.27 1.27)
				)
			)
		)
		(property "Value" ""
			(at 0 0 180)
			(layer "F.Fab")
			(effects
				(font
					(size 1.27 1.27)
				)
			)
		)
		(duplicate_pad_numbers_are_jumpers no)
		(fp_line
			(start 0.7874 0.4064)
			(end -0.7874 0.4064)
			(stroke
				(width 0.1524)
				(type default)
			)
			(layer "F.SilkS")
		)
		(fp_line
			(start 0.7874 -0.4064)
			(end 0.7874 0.4064)
			(stroke
				(width 0.1524)
				(type default)
			)
			(layer "F.SilkS")
		)
		(fp_line
			(start -0.7874 0.4064)
			(end -0.7874 -0.4064)
			(stroke
				(width 0.1524)
				(type default)
			)
			(layer "F.SilkS")
		)
		(fp_line
			(start -0.7874 -0.4064)
			(end 0.7874 -0.4064)
			(stroke
				(width 0.1524)
				(type default)
			)
			(layer "F.SilkS")
		)
		(fp_line
			(start 0.67945 0.3048)
			(end 0.120396 0.3048)
			(stroke
				(width 0.1)
				(type default)
			)
			(layer "F.Fab")
		)
		(fp_line
			(start 0.67945 -0.3048)
			(end 0.67945 0.3048)
			(stroke
				(width 0.1)
				(type default)
			)
			(layer "F.Fab")
		)
		(fp_line
			(start 0.12065 -0.2794)
			(end 0.12065 -0.3048)
			(stroke
				(width 0.1)
				(type default)
			)
			(layer "F.Fab")
		)
		(fp_line
			(start 0.12065 -0.3048)
			(end 0.67945 -0.3048)
			(stroke
				(width 0.1)
				(type default)
			)
			(layer "F.Fab")
		)
		(fp_line
			(start 0.120396 0.3048)
			(end 0.120396 0.2794)
			(stroke
				(width 0.1)
				(type default)
			)
			(layer "F.Fab")
		)
		(fp_line
			(start 0.120396 0.2794)
			(end -0.12065 0.2794)
			(stroke
				(width 0.1)
				(type default)
			)
			(layer "F.Fab")
		)
		(fp_line
			(start -0.12065 0.3048)
			(end -0.67945 0.3048)
			(stroke
				(width 0.1)
				(type default)
			)
			(layer "F.Fab")
		)
		(fp_line
			(start -0.12065 0.2794)
			(end -0.12065 0.3048)
			(stroke
				(width 0.1)
				(type default)
			)
			(layer "F.Fab")
		)
		(fp_line
			(start -0.12065 -0.2794)
			(end 0.12065 -0.2794)
			(stroke
				(width 0.1)
				(type default)
			)
			(layer "F.Fab")
		)
		(fp_line
			(start -0.12065 -0.305054)
			(end -0.12065 -0.2794)
			(stroke
				(width 0.1)
				(type default)
			)
			(layer "F.Fab")
		)
		(fp_line
			(start -0.67945 0.3048)
			(end -0.67945 -0.305054)
			(stroke
				(width 0.1)
				(type default)
			)
			(layer "F.Fab")
		)
		(fp_line
			(start -0.67945 -0.305054)
			(end -0.12065 -0.305054)
			(stroke
				(width 0.1)
				(type default)
			)
			(layer "F.Fab")
		)
		(pad "1" smd circle
			(at -0.40005 0 180)
			(size 0 0)
			(layers "F.Cu" "F.Mask" "F.Paste")
			(net "P3V3_AUX")
		)
		(pad "2" smd circle
			(at 0.40005 0 180)
			(size 0 0)
			(layers "F.Cu" "F.Mask" "F.Paste")
			(net "GND")
		)
	)
	(footprint ""
		(layer "F.Cu")
		(at 245.553484 -236.675168 -90)
		(property "Reference" "C3989"
			(at 0 0 270)
			(layer "F.SilkS")
			(hide yes)
			(effects
				(font
					(size 1.27 1.27)
				)
			)
		)
		(property "Value" ""
			(at 0 0 270)
			(layer "F.Fab")
			(effects
				(font
					(size 1.27 1.27)
				)
			)
		)
		(duplicate_pad_numbers_are_jumpers no)
		(fp_line
			(start -0.7874 0.4064)
			(end -0.7874 -0.4064)
			(stroke
				(width 0.1524)
				(type default)
			)
			(layer "F.SilkS")
		)
		(fp_line
			(start 0.7874 0.4064)
			(end -0.7874 0.4064)
			(stroke
				(width 0.1524)
				(type default)
			)
			(layer "F.SilkS")
		)
		(fp_line
			(start -0.7874 -0.4064)
			(end 0.7874 -0.4064)
			(stroke
				(width 0.1524)
				(type default)
			)
			(layer "F.SilkS")
		)
		(fp_line
			(start 0.7874 -0.4064)
			(end 0.7874 0.4064)
			(stroke
				(width 0.1524)
				(type default)
			)
			(layer "F.SilkS")
		)
		(fp_line
			(start -0.67945 0.3048)
			(end -0.67945 -0.305054)
			(stroke
				(width 0.1)
				(type default)
			)
			(layer "F.Fab")
		)
		(fp_line
			(start -0.12065 0.3048)
			(end -0.67945 0.3048)
			(stroke
				(width 0.1)
				(type default)
			)
			(layer "F.Fab")
		)
		(fp_line
			(start 0.120396 0.3048)
			(end 0.120396 0.2794)
			(stroke
				(width 0.1)
				(type default)
			)
			(layer "F.Fab")
		)
		(fp_line
			(start 0.67945 0.3048)
			(end 0.120396 0.3048)
			(stroke
				(width 0.1)
				(type default)
			)
			(layer "F.Fab")
		)
		(fp_line
			(start -0.12065 0.2794)
			(end -0.12065 0.3048)
			(stroke
				(width 0.1)
				(type default)
			)
			(layer "F.Fab")
		)
		(fp_line
			(start 0.120396 0.2794)
			(end -0.12065 0.2794)
			(stroke
				(width 0.1)
				(type default)
			)
			(layer "F.Fab")
		)
		(fp_line
			(start -0.12065 -0.2794)
			(end 0.12065 -0.2794)
			(stroke
				(width 0.1)
				(type default)
			)
			(layer "F.Fab")
		)
		(fp_line
			(start 0.12065 -0.2794)
			(end 0.12065 -0.3048)
			(stroke
				(width 0.1)
				(type default)
			)
			(layer "F.Fab")
		)
		(fp_line
			(start 0.12065 -0.3048)
			(end 0.67945 -0.3048)
			(stroke
				(width 0.1)
				(type default)
			)
			(layer "F.Fab")
		)
		(fp_line
			(start 0.67945 -0.3048)
			(end 0.67945 0.3048)
			(stroke
				(width 0.1)
				(type default)
			)
			(layer "F.Fab")
		)
		(fp_line
			(start -0.67945 -0.305054)
			(end -0.12065 -0.305054)
			(stroke
				(width 0.1)
				(type default)
			)
			(layer "F.Fab")
		)
		(fp_line
			(start -0.12065 -0.305054)
			(end -0.12065 -0.2794)
			(stroke
				(width 0.1)
				(type default)
			)
			(layer "F.Fab")
		)
		(pad "1" smd circle
			(at -0.40005 0 270)
			(size 0 0)
			(layers "F.Cu" "F.Mask" "F.Paste")
			(net "P3V3_AUX")
		)
		(pad "2" smd circle
			(at 0.40005 0 270)
			(size 0 0)
			(layers "F.Cu" "F.Mask" "F.Paste")
			(net "GND")
		)
	)
	(footprint ""
		(layer "F.Cu")
		(at 214.534496 -34.546286 180)
		(property "Reference" "C300"
			(at 0 0 180)
			(layer "F.SilkS")
			(hide yes)
			(effects
				(font
					(size 1.27 1.27)
				)
			)
		)
		(property "Value" ""
			(at 0 0 180)
			(layer "F.Fab")
			(effects
				(font
					(size 1.27 1.27)
				)
			)
		)
		(duplicate_pad_numbers_are_jumpers no)
		(fp_line
			(start 0.299974 0.150114)
			(end -0.299974 0.150114)
			(stroke
				(width 0.1)
				(type default)
			)
			(layer "F.Fab")
		)
		(fp_line
			(start 0.299974 -0.150114)
			(end 0.299974 0.150114)
			(stroke
				(width 0.1)
				(type default)
			)
			(layer "F.Fab")
		)
		(fp_line
			(start -0.299974 0.150114)
			(end -0.299974 -0.150114)
			(stroke
				(width 0.1)
				(type default)
			)
			(layer "F.Fab")
		)
		(fp_line
			(start -0.299974 -0.150114)
			(end 0.299974 -0.150114)
			(stroke
				(width 0.1)
				(type default)
			)
			(layer "F.Fab")
		)
		(pad "1" smd rect
			(at -0.2667 0 180)
			(size 0.3048 0.381)
			(layers "F.Cu" "F.Mask" "F.Paste")
			(net "P5E_PEX1_STN2_TX_DP<35>")
		)
		(pad "2" smd rect
			(at 0.2667 0 180)
			(size 0.3048 0.381)
			(layers "F.Cu" "F.Mask" "F.Paste")
			(net "P5E_PEX1_STN2_TX_C_DP<35>")
		)
	)
)
